(kicad_pcb
	(version 20260206)
	(generator "pcbnew")
	(generator_version "10.0")
	(general
		(thickness 1.6)
		(legacy_teardrops no)
	)
	(paper "A4")
	(title_block
		(title "04192023_DAF0TMB3IC0_F0TG_MB_C_brd_V02_OCP.brd")
		(comment 1 "Grand Teton / footprint 2783 of 8354 (U26), pads 1650-1762 of 6102")
	)
	(layers
		(0 "F.Cu" signal "TOP")
		(4 "In1.Cu" signal "GND")
		(6 "In2.Cu" signal "IN1")
		(8 "In3.Cu" signal "GND1")
		(10 "In4.Cu" signal "IN2")
		(12 "In5.Cu" signal "GND2")
		(14 "In6.Cu" signal "IN3")
		(16 "In7.Cu" signal "GND3")
		(18 "In8.Cu" signal "VCC")
		(20 "In9.Cu" signal "VCC1")
		(22 "In10.Cu" signal "GND4")
		(24 "In11.Cu" signal "IN4")
		(26 "In12.Cu" signal "GND5")
		(28 "In13.Cu" signal "IN5")
		(30 "In14.Cu" signal "GND6")
		(32 "In15.Cu" signal "IN6")
		(34 "In16.Cu" signal "GND7")
		(2 "B.Cu" signal "BOTTOM")
		(9 "F.Adhes" user "F.Adhesive")
		(11 "B.Adhes" user "B.Adhesive")
		(13 "F.Paste" user "Package Geometry/Pastemask Top")
		(15 "B.Paste" user "Package Geometry/Pastemask Bottom")
		(5 "F.SilkS" user "Ref Des/Silkscreen Top")
		(7 "B.SilkS" user "Ref Des/Silkscreen Bottom")
		(1 "F.Mask" user "Board Geometry/Soldermask Top")
		(3 "B.Mask" user "Board Geometry/Soldermask Bottom")
		(17 "Dwgs.User" user "User.Drawings")
		(19 "Cmts.User" user "User.Comments")
		(21 "Eco1.User" user "User.Eco1")
		(23 "Eco2.User" user "User.Eco2")
		(25 "Edge.Cuts" user "Board Geometry/Outline")
		(27 "Margin" user)
		(31 "F.CrtYd" user "Package Geometry/Place Bound Top")
		(29 "B.CrtYd" user "Package Geometry/Place Bound Bottom")
		(35 "F.Fab" user "Ref Des/Assembly Top")
		(33 "B.Fab" user "Ref Des/Assembly Bottom")
	)
	(footprint ""
		(layer "F.Cu")
		(at 111.927894 -258.880356 180)
		(property "Reference" "U26"
			(at -45.05579 -61.794136 0)
			(unlocked yes)
			(layer "F.SilkS")
			(effects
				(font
					(size 0.7874 0.5842)
					(thickness 0.1524)
				)
			)
		)
		(property "Value" ""
			(at 0 0 180)
			(layer "F.Fab")
			(effects
				(font
					(size 1.27 1.27)
				)
			)
		)
		(duplicate_pad_numbers_are_jumpers no)
		(pad "BC2" smd circle
			(at -33.219898 -2.789936 180)
			(size 0.450088 0.450088)
			(layers "F.Cu" "F.Mask" "F.Paste")
			(net "M_G_CPU1_CLK_DP<0>")
		)
		(pad "BC3" smd circle
			(at -32.280098 -2.789936 180)
			(size 0.450088 0.450088)
			(layers "F.Cu" "F.Mask" "F.Paste")
			(net "M_G_CPU1_SA_PAR")
		)
		(pad "BC4" smd circle
			(at -31.340044 -2.789936 180)
			(size 0.450088 0.450088)
			(layers "F.Cu" "F.Mask" "F.Paste")
			(net "GND")
		)
		(pad "BC5" smd circle
			(at -30.39999 -2.789936 180)
			(size 0.450088 0.450088)
			(layers "F.Cu" "F.Mask" "F.Paste")
			(net "M_K_CPU1_CLK_DP<0>")
		)
		(pad "BC6" smd circle
			(at -29.459936 -2.789936 180)
			(size 0.450088 0.450088)
			(layers "F.Cu" "F.Mask" "F.Paste")
			(net "GND")
		)
		(pad "BC7" smd circle
			(at -28.519882 -2.789936 180)
			(size 0.450088 0.450088)
			(layers "F.Cu" "F.Mask" "F.Paste")
			(net "M_K_CPU1_SA_PAR")
		)
		(pad "BC8" smd circle
			(at -27.580082 -2.789936 180)
			(size 0.450088 0.450088)
			(layers "F.Cu" "F.Mask" "F.Paste")
			(net "GND")
		)
		(pad "BC9" smd circle
			(at -26.640028 -2.789936 180)
			(size 0.450088 0.450088)
			(layers "F.Cu" "F.Mask" "F.Paste")
			(net "M_L_CPU1_CLK_DP<0>")
		)
		(pad "BC10" smd circle
			(at -25.699974 -2.789936 180)
			(size 0.450088 0.450088)
			(layers "F.Cu" "F.Mask" "F.Paste")
			(net "M_L_CPU1_SA_PAR")
		)
		(pad "BC11" smd circle
			(at -24.75992 -2.789936 180)
			(size 0.450088 0.450088)
			(layers "F.Cu" "F.Mask" "F.Paste")
			(net "GND")
		)
		(pad "BC12" smd circle
			(at -23.82012 -2.789936 180)
			(size 0.450088 0.450088)
			(layers "F.Cu" "F.Mask" "F.Paste")
			(net "M_H_CPU1_CLK_DP<0>")
		)
		(pad "BC13" smd circle
			(at -22.880066 -2.789936 180)
			(size 0.450088 0.450088)
			(layers "F.Cu" "F.Mask" "F.Paste")
			(net "GND")
		)
		(pad "BC14" smd circle
			(at -21.940012 -2.789936 180)
			(size 0.450088 0.450088)
			(layers "F.Cu" "F.Mask" "F.Paste")
			(net "M_H_CPU1_SA_PAR")
		)
		(pad "BC15" smd circle
			(at -20.999958 -2.789936 180)
			(size 0.450088 0.450088)
			(layers "F.Cu" "F.Mask" "F.Paste")
			(net "GND")
		)
		(pad "BC16" smd circle
			(at -20.059904 -2.789936 180)
			(size 0.450088 0.450088)
			(layers "F.Cu" "F.Mask" "F.Paste")
			(net "M_J_CPU1_CLK_DP<0>")
		)
		(pad "BC17" smd circle
			(at -19.120104 -2.789936 180)
			(size 0.450088 0.450088)
			(layers "F.Cu" "F.Mask" "F.Paste")
			(net "M_J_CPU1_SA_PAR")
		)
		(pad "BC18" smd circle
			(at -18.18005 -2.789936 180)
			(size 0.450088 0.450088)
			(layers "F.Cu" "F.Mask" "F.Paste")
			(net "GND")
		)
		(pad "BC19" smd circle
			(at -17.239996 -2.789936 180)
			(size 0.450088 0.450088)
			(layers "F.Cu" "F.Mask" "F.Paste")
			(net "M_I_CPU1_CLK_DP<0>")
		)
		(pad "BC20" smd circle
			(at -16.299942 -2.789936 180)
			(size 0.450088 0.450088)
			(layers "F.Cu" "F.Mask" "F.Paste")
			(net "GND")
		)
		(pad "BC21" smd circle
			(at -15.359888 -2.789936 180)
			(size 0.450088 0.450088)
			(layers "F.Cu" "F.Mask" "F.Paste")
			(net "M_I_CPU1_SA_PAR")
		)
		(pad "BC22" smd circle
			(at -14.420088 -2.789936 180)
			(size 0.450088 0.450088)
			(layers "F.Cu" "F.Mask" "F.Paste")
			(net "GND")
		)
		(pad "BC23" smd circle
			(at -13.480034 -2.789936 180)
			(size 0.450088 0.450088)
			(layers "F.Cu" "F.Mask" "F.Paste")
			(net "PVDDCR_SOC_P1")
		)
		(pad "BC24" smd circle
			(at -12.53998 -2.789936 180)
			(size 0.450088 0.450088)
			(layers "F.Cu" "F.Mask" "F.Paste")
			(net "GND")
		)
		(pad "BC25" smd circle
			(at -11.599926 -2.789936 180)
			(size 0.450088 0.450088)
			(layers "F.Cu" "F.Mask" "F.Paste")
			(net "PVDDCR_SOC_P1")
		)
		(pad "BC26" smd circle
			(at -10.659872 -2.789936 180)
			(size 0.450088 0.450088)
			(layers "F.Cu" "F.Mask" "F.Paste")
			(net "GND")
		)
		(pad "BC27" smd circle
			(at -9.720072 -2.789936 180)
			(size 0.450088 0.450088)
			(layers "F.Cu" "F.Mask" "F.Paste")
			(net "PVDDCR_SOC_P1")
		)
		(pad "BC28" smd circle
			(at -8.780018 -2.789936 180)
			(size 0.450088 0.450088)
			(layers "F.Cu" "F.Mask" "F.Paste")
			(net "GND")
		)
		(pad "BC48" smd circle
			(at 9.079992 -2.789936 180)
			(size 0.450088 0.450088)
			(layers "F.Cu" "F.Mask" "F.Paste")
			(net "PVDDCR_SOC_P1")
		)
		(pad "BC49" smd circle
			(at 10.020046 -2.789936 180)
			(size 0.450088 0.450088)
			(layers "F.Cu" "F.Mask" "F.Paste")
			(net "GND")
		)
		(pad "BC50" smd circle
			(at 10.9601 -2.789936 180)
			(size 0.450088 0.450088)
			(layers "F.Cu" "F.Mask" "F.Paste")
			(net "GND")
		)
		(pad "BC51" smd circle
			(at 11.8999 -2.789936 180)
			(size 0.450088 0.450088)
			(layers "F.Cu" "F.Mask" "F.Paste")
			(net "GND")
		)
		(pad "BC52" smd circle
			(at 12.839954 -2.789936 180)
			(size 0.450088 0.450088)
			(layers "F.Cu" "F.Mask" "F.Paste")
			(net "PVDD18_S5_P1")
		)
		(pad "BC53" smd circle
			(at 13.780008 -2.789936 180)
			(size 0.450088 0.450088)
			(layers "F.Cu" "F.Mask" "F.Paste")
			(net "GND")
		)
		(pad "BC54" smd circle
			(at 14.720062 -2.789936 180)
			(size 0.450088 0.450088)
			(layers "F.Cu" "F.Mask" "F.Paste")
			(net "PVDD18_S5_P1")
		)
		(pad "BC55" smd circle
			(at 15.660116 -2.789936 180)
			(size 0.450088 0.450088)
			(layers "F.Cu" "F.Mask" "F.Paste")
			(net "M_C_CPU1_SA_PAR")
		)
		(pad "BC56" smd circle
			(at 16.599916 -2.789936 180)
			(size 0.450088 0.450088)
			(layers "F.Cu" "F.Mask" "F.Paste")
			(net "GND")
		)
		(pad "BC57" smd circle
			(at 17.53997 -2.789936 180)
			(size 0.450088 0.450088)
			(layers "F.Cu" "F.Mask" "F.Paste")
			(net "M_C_CPU1_CLK_DP<0>")
		)
		(pad "BC58" smd circle
			(at 18.480024 -2.789936 180)
			(size 0.450088 0.450088)
			(layers "F.Cu" "F.Mask" "F.Paste")
			(net "GND")
		)
		(pad "BC59" smd circle
			(at 19.420078 -2.789936 180)
			(size 0.450088 0.450088)
			(layers "F.Cu" "F.Mask" "F.Paste")
			(net "M_D_CPU1_SA_PAR")
		)
		(pad "BC60" smd circle
			(at 20.359878 -2.789936 180)
			(size 0.450088 0.450088)
			(layers "F.Cu" "F.Mask" "F.Paste")
			(net "M_D_CPU1_CLK_DP<0>")
		)
		(pad "BC61" smd circle
			(at 21.299932 -2.789936 180)
			(size 0.450088 0.450088)
			(layers "F.Cu" "F.Mask" "F.Paste")
			(net "GND")
		)
		(pad "BC62" smd circle
			(at 22.239986 -2.789936 180)
			(size 0.450088 0.450088)
			(layers "F.Cu" "F.Mask" "F.Paste")
			(net "M_B_CPU1_SA_PAR")
		)
		(pad "BC63" smd circle
			(at 23.18004 -2.789936 180)
			(size 0.450088 0.450088)
			(layers "F.Cu" "F.Mask" "F.Paste")
			(net "GND")
		)
		(pad "BC64" smd circle
			(at 24.120094 -2.789936 180)
			(size 0.450088 0.450088)
			(layers "F.Cu" "F.Mask" "F.Paste")
			(net "M_B_CPU1_CLK_DP<0>")
		)
		(pad "BC65" smd circle
			(at 25.059894 -2.789936 180)
			(size 0.450088 0.450088)
			(layers "F.Cu" "F.Mask" "F.Paste")
			(net "GND")
		)
		(pad "BC66" smd circle
			(at 25.999948 -2.789936 180)
			(size 0.450088 0.450088)
			(layers "F.Cu" "F.Mask" "F.Paste")
			(net "M_F_CPU1_SA_PAR")
		)
		(pad "BC67" smd circle
			(at 26.940002 -2.789936 180)
			(size 0.450088 0.450088)
			(layers "F.Cu" "F.Mask" "F.Paste")
			(net "M_F_CPU1_CLK_DP<0>")
		)
		(pad "BC68" smd circle
			(at 27.880056 -2.789936 180)
			(size 0.450088 0.450088)
			(layers "F.Cu" "F.Mask" "F.Paste")
			(net "GND")
		)
		(pad "BC69" smd circle
			(at 28.82011 -2.789936 180)
			(size 0.450088 0.450088)
			(layers "F.Cu" "F.Mask" "F.Paste")
			(net "M_E_CPU1_SA_PAR")
		)
		(pad "BC70" smd circle
			(at 29.75991 -2.789936 180)
			(size 0.450088 0.450088)
			(layers "F.Cu" "F.Mask" "F.Paste")
			(net "GND")
		)
		(pad "BC71" smd circle
			(at 30.699964 -2.789936 180)
			(size 0.450088 0.450088)
			(layers "F.Cu" "F.Mask" "F.Paste")
			(net "M_E_CPU1_CLK_DP<0>")
		)
		(pad "BC72" smd circle
			(at 31.640018 -2.789936 180)
			(size 0.450088 0.450088)
			(layers "F.Cu" "F.Mask" "F.Paste")
			(net "GND")
		)
		(pad "BC73" smd circle
			(at 32.580072 -2.789936 180)
			(size 0.450088 0.450088)
			(layers "F.Cu" "F.Mask" "F.Paste")
			(net "M_A_CPU1_SA_PAR")
		)
		(pad "BC74" smd circle
			(at 33.519872 -2.789936 180)
			(size 0.450088 0.450088)
			(layers "F.Cu" "F.Mask" "F.Paste")
			(net "M_A_CPU1_CLK_DP<0>")
		)
		(pad "BC75" smd circle
			(at 34.459926 -2.789936 180)
			(size 0.450088 0.450088)
			(layers "F.Cu" "F.Mask" "F.Paste")
			(net "GND")
		)
		(pad "BD2" smd circle
			(at -33.690052 -1.97993 180)
			(size 0.450088 0.450088)
			(layers "F.Cu" "F.Mask" "F.Paste")
			(net "M_G_CPU1_CLK_DN<0>")
		)
		(pad "BD3" smd circle
			(at -32.749998 -1.97993 180)
			(size 0.450088 0.450088)
			(layers "F.Cu" "F.Mask" "F.Paste")
			(net "GND")
		)
		(pad "BD4" smd circle
			(at -31.809944 -1.97993 180)
			(size 0.450088 0.450088)
			(layers "F.Cu" "F.Mask" "F.Paste")
			(net "Net_2140")
		)
		(pad "BD5" smd circle
			(at -30.86989 -1.97993 180)
			(size 0.450088 0.450088)
			(layers "F.Cu" "F.Mask" "F.Paste")
			(net "PVDDCR_SOC_P1")
		)
		(pad "BD6" smd circle
			(at -29.93009 -1.97993 180)
			(size 0.450088 0.450088)
			(layers "F.Cu" "F.Mask" "F.Paste")
			(net "M_K_CPU1_CLK_DN<0>")
		)
		(pad "BD7" smd circle
			(at -28.990036 -1.97993 180)
			(size 0.450088 0.450088)
			(layers "F.Cu" "F.Mask" "F.Paste")
			(net "Net_2146")
		)
		(pad "BD8" smd circle
			(at -28.049982 -1.97993 180)
			(size 0.450088 0.450088)
			(layers "F.Cu" "F.Mask" "F.Paste")
			(net "GND")
		)
		(pad "BD9" smd circle
			(at -27.109928 -1.97993 180)
			(size 0.450088 0.450088)
			(layers "F.Cu" "F.Mask" "F.Paste")
			(net "M_L_CPU1_CLK_DN<0>")
		)
		(pad "BD10" smd circle
			(at -26.170128 -1.97993 180)
			(size 0.450088 0.450088)
			(layers "F.Cu" "F.Mask" "F.Paste")
			(net "GND")
		)
		(pad "BD11" smd circle
			(at -25.230074 -1.97993 180)
			(size 0.450088 0.450088)
			(layers "F.Cu" "F.Mask" "F.Paste")
			(net "Net_2136")
		)
		(pad "BD12" smd circle
			(at -24.29002 -1.97993 180)
			(size 0.450088 0.450088)
			(layers "F.Cu" "F.Mask" "F.Paste")
			(net "PVDDCR_SOC_P1")
		)
		(pad "BD13" smd circle
			(at -23.349966 -1.97993 180)
			(size 0.450088 0.450088)
			(layers "F.Cu" "F.Mask" "F.Paste")
			(net "M_H_CPU1_CLK_DN<0>")
		)
		(pad "BD14" smd circle
			(at -22.409912 -1.97993 180)
			(size 0.450088 0.450088)
			(layers "F.Cu" "F.Mask" "F.Paste")
			(net "Net_2137")
		)
		(pad "BD15" smd circle
			(at -21.470112 -1.97993 180)
			(size 0.450088 0.450088)
			(layers "F.Cu" "F.Mask" "F.Paste")
			(net "GND")
		)
		(pad "BD16" smd circle
			(at -20.530058 -1.97993 180)
			(size 0.450088 0.450088)
			(layers "F.Cu" "F.Mask" "F.Paste")
			(net "M_J_CPU1_CLK_DN<0>")
		)
		(pad "BD17" smd circle
			(at -19.590004 -1.97993 180)
			(size 0.450088 0.450088)
			(layers "F.Cu" "F.Mask" "F.Paste")
			(net "GND")
		)
		(pad "BD18" smd circle
			(at -18.64995 -1.97993 180)
			(size 0.450088 0.450088)
			(layers "F.Cu" "F.Mask" "F.Paste")
			(net "Net_2138")
		)
		(pad "BD19" smd circle
			(at -17.709896 -1.97993 180)
			(size 0.450088 0.450088)
			(layers "F.Cu" "F.Mask" "F.Paste")
			(net "PVDDCR_SOC_P1")
		)
		(pad "BD20" smd circle
			(at -16.770096 -1.97993 180)
			(size 0.450088 0.450088)
			(layers "F.Cu" "F.Mask" "F.Paste")
			(net "M_I_CPU1_CLK_DN<0>")
		)
		(pad "BD21" smd circle
			(at -15.830042 -1.97993 180)
			(size 0.450088 0.450088)
			(layers "F.Cu" "F.Mask" "F.Paste")
			(net "Net_2139")
		)
		(pad "BD22" smd circle
			(at -14.889988 -1.97993 180)
			(size 0.450088 0.450088)
			(layers "F.Cu" "F.Mask" "F.Paste")
			(net "PVDDCR_SOC_P1")
		)
		(pad "BD23" smd circle
			(at -13.949934 -1.97993 180)
			(size 0.450088 0.450088)
			(layers "F.Cu" "F.Mask" "F.Paste")
			(net "GND")
		)
		(pad "BD24" smd circle
			(at -13.00988 -1.97993 180)
			(size 0.450088 0.450088)
			(layers "F.Cu" "F.Mask" "F.Paste")
			(net "PVDDCR_SOC_P1")
		)
		(pad "BD25" smd circle
			(at -12.07008 -1.97993 180)
			(size 0.450088 0.450088)
			(layers "F.Cu" "F.Mask" "F.Paste")
			(net "GND")
		)
		(pad "BD26" smd circle
			(at -11.130026 -1.97993 180)
			(size 0.450088 0.450088)
			(layers "F.Cu" "F.Mask" "F.Paste")
			(net "PVDDCR_SOC_P1")
		)
		(pad "BD27" smd circle
			(at -10.189972 -1.97993 180)
			(size 0.450088 0.450088)
			(layers "F.Cu" "F.Mask" "F.Paste")
			(net "GND")
		)
		(pad "BD28" smd circle
			(at -9.249918 -1.97993 180)
			(size 0.450088 0.450088)
			(layers "F.Cu" "F.Mask" "F.Paste")
			(net "PVDDCR_SOC_P1")
		)
		(pad "BD48" smd circle
			(at 9.549892 -1.97993 180)
			(size 0.450088 0.450088)
			(layers "F.Cu" "F.Mask" "F.Paste")
			(net "PVDDCR_SOC_P1")
		)
		(pad "BD49" smd circle
			(at 10.489946 -1.97993 180)
			(size 0.450088 0.450088)
			(layers "F.Cu" "F.Mask" "F.Paste")
			(net "GND")
		)
		(pad "BD50" smd circle
			(at 11.43 -1.97993 180)
			(size 0.450088 0.450088)
			(layers "F.Cu" "F.Mask" "F.Paste")
			(net "PVDDIO_P1")
		)
		(pad "BD51" smd circle
			(at 12.370054 -1.97993 180)
			(size 0.450088 0.450088)
			(layers "F.Cu" "F.Mask" "F.Paste")
			(net "GND")
		)
		(pad "BD52" smd circle
			(at 13.310108 -1.97993 180)
			(size 0.450088 0.450088)
			(layers "F.Cu" "F.Mask" "F.Paste")
			(net "PVDDIO_P1")
		)
		(pad "BD53" smd circle
			(at 14.249908 -1.97993 180)
			(size 0.450088 0.450088)
			(layers "F.Cu" "F.Mask" "F.Paste")
			(net "GND")
		)
		(pad "BD54" smd circle
			(at 15.189962 -1.97993 180)
			(size 0.450088 0.450088)
			(layers "F.Cu" "F.Mask" "F.Paste")
			(net "PVDDIO_P1")
		)
		(pad "BD55" smd circle
			(at 16.130016 -1.97993 180)
			(size 0.450088 0.450088)
			(layers "F.Cu" "F.Mask" "F.Paste")
			(net "Net_2141")
		)
		(pad "BD56" smd circle
			(at 17.07007 -1.97993 180)
			(size 0.450088 0.450088)
			(layers "F.Cu" "F.Mask" "F.Paste")
			(net "M_C_CPU1_CLK_DN<0>")
		)
		(pad "BD57" smd circle
			(at 18.010124 -1.97993 180)
			(size 0.450088 0.450088)
			(layers "F.Cu" "F.Mask" "F.Paste")
			(net "GND")
		)
		(pad "BD58" smd circle
			(at 18.949924 -1.97993 180)
			(size 0.450088 0.450088)
			(layers "F.Cu" "F.Mask" "F.Paste")
			(net "Net_2142")
		)
		(pad "BD59" smd circle
			(at 19.889978 -1.97993 180)
			(size 0.450088 0.450088)
			(layers "F.Cu" "F.Mask" "F.Paste")
			(net "GND")
		)
		(pad "BD60" smd circle
			(at 20.830032 -1.97993 180)
			(size 0.450088 0.450088)
			(layers "F.Cu" "F.Mask" "F.Paste")
			(net "M_D_CPU1_CLK_DN<0>")
		)
		(pad "BD61" smd circle
			(at 21.770086 -1.97993 180)
			(size 0.450088 0.450088)
			(layers "F.Cu" "F.Mask" "F.Paste")
			(net "GND")
		)
		(pad "BD62" smd circle
			(at 22.709886 -1.97993 180)
			(size 0.450088 0.450088)
			(layers "F.Cu" "F.Mask" "F.Paste")
			(net "Net_2143")
		)
		(pad "BD63" smd circle
			(at 23.64994 -1.97993 180)
			(size 0.450088 0.450088)
			(layers "F.Cu" "F.Mask" "F.Paste")
			(net "M_B_CPU1_CLK_DN<0>")
		)
		(pad "BD64" smd circle
			(at 24.589994 -1.97993 180)
			(size 0.450088 0.450088)
			(layers "F.Cu" "F.Mask" "F.Paste")
			(net "GND")
		)
		(pad "BD65" smd circle
			(at 25.530048 -1.97993 180)
			(size 0.450088 0.450088)
			(layers "F.Cu" "F.Mask" "F.Paste")
			(net "Net_2144")
		)
		(pad "BD66" smd circle
			(at 26.470102 -1.97993 180)
			(size 0.450088 0.450088)
			(layers "F.Cu" "F.Mask" "F.Paste")
			(net "GND")
		)
		(pad "BD67" smd circle
			(at 27.409902 -1.97993 180)
			(size 0.450088 0.450088)
			(layers "F.Cu" "F.Mask" "F.Paste")
			(net "M_F_CPU1_CLK_DN<0>")
		)
		(pad "BD68" smd circle
			(at 28.349956 -1.97993 180)
			(size 0.450088 0.450088)
			(layers "F.Cu" "F.Mask" "F.Paste")
			(net "GND")
		)
		(pad "BD69" smd circle
			(at 29.29001 -1.97993 180)
			(size 0.450088 0.450088)
			(layers "F.Cu" "F.Mask" "F.Paste")
			(net "Net_2145")
		)
		(pad "BD70" smd circle
			(at 30.230064 -1.97993 180)
			(size 0.450088 0.450088)
			(layers "F.Cu" "F.Mask" "F.Paste")
			(net "M_E_CPU1_CLK_DN<0>")
		)
		(pad "BD71" smd circle
			(at 31.170118 -1.97993 180)
			(size 0.450088 0.450088)
			(layers "F.Cu" "F.Mask" "F.Paste")
			(net "GND")
		)
		(pad "BD72" smd circle
			(at 32.109918 -1.97993 180)
			(size 0.450088 0.450088)
			(layers "F.Cu" "F.Mask" "F.Paste")
			(net "Net_2147")
		)
		(pad "BD73" smd circle
			(at 33.049972 -1.97993 180)
			(size 0.450088 0.450088)
			(layers "F.Cu" "F.Mask" "F.Paste")
			(net "GND")
		)
		(pad "BD74" smd circle
			(at 33.990026 -1.97993 180)
			(size 0.450088 0.450088)
			(layers "F.Cu" "F.Mask" "F.Paste")
			(net "M_A_CPU1_CLK_DN<0>")
		)
		(pad "BF2" smd circle
			(at -33.990026 1.97993 180)
			(size 0.450088 0.450088)
			(layers "F.Cu" "F.Mask" "F.Paste")
			(net "Net_2038")
		)
		(pad "BF3" smd circle
			(at -33.049972 1.97993 180)
			(size 0.450088 0.450088)
			(layers "F.Cu" "F.Mask" "F.Paste")
			(net "GND")
		)
		(pad "BF4" smd circle
			(at -32.109918 1.97993 180)
			(size 0.450088 0.450088)
			(layers "F.Cu" "F.Mask" "F.Paste")
			(net "TP_M_G_CPU1_SA_TEST39G")
		)
		(pad "BF5" smd circle
			(at -31.170118 1.97993 180)
			(size 0.450088 0.450088)
			(layers "F.Cu" "F.Mask" "F.Paste")
			(net "GND")
		)
	)
)
